# S9S_MB_2U (Grand Teton) — schematic parts with pin connectivity, parts 1601–1601 of 6093; source: Cadence DE-HDL packaged netlist (pstxprt.dat, pstxnet.dat, pstchip.dat)

J8  SCONN288_ADR50017P087CC  SCONN288_ADR50017-P087CC IO  pkg DDR288S_1-1VXB  page 89
  1  VIN_BULK0  POWER  = P12V_S3_AUX_CPU0_NVDIMM
  2  RFU0  TRI  = TP_CHD_CPU0_DIMM2_FRU_0
  3  VIN_MGMT  POWER  = P3V3_AUX
  4  HSCL  IN  = I3C_SPD_DDRABCD_CPU0_LVC1_SCL_7
  5  HSDA  BI  = I3C_SPD_DDRABCD_CPU0_LVC1_SDA
  6  VSS0  POWER  = GND
  7  DQ0_A  BI  = M_D_CPU0_SA_DQ<0>
  8  VSS1  POWER  = GND
  9  DQ1_A  BI  = M_D_CPU0_SA_DQ<1>
  10  VSS2  POWER  = GND
  11  DQS0_A_T  BI  = M_D_CPU0_SA_DQS_DP<0>
  12  DQS0_A_C  BI  = M_D_CPU0_SA_DQS_DN<0>
  13  VSS3  POWER  = GND
  14  DQ4_A  BI  = M_D_CPU0_SA_DQ<4>
  15  VSS4  POWER  = GND
  16  DQ5_A  BI  = M_D_CPU0_SA_DQ<5>
  17  VSS5  POWER  = GND
  18  DQ8_A  BI  = M_D_CPU0_SA_DQ<8>
  19  VSS6  POWER  = GND
  20  DQ9_A  BI  = M_D_CPU0_SA_DQ<9>
  21  VSS7  POWER  = GND
  22  DQS1_A_T  BI  = M_D_CPU0_SA_DQS_DP<1>
  23  DQS1_A_C  BI  = M_D_CPU0_SA_DQS_DN<1>
  24  VSS8  POWER  = GND
  25  DQ12_A  BI  = M_D_CPU0_SA_DQ<12>
  26  VSS9  POWER  = GND
  27  DQ13_A  BI  = M_D_CPU0_SA_DQ<13>
  28  VSS10  POWER  = GND
  29  DQ16_A  BI  = M_D_CPU0_SA_DQ<16>
  30  VSS11  POWER  = GND
  31  DQ17_A  BI  = M_D_CPU0_SA_DQ<17>
  32  VSS12  POWER  = GND
  33  DQS2_A_T  BI  = M_D_CPU0_SA_DQS_DP<2>
  34  DQS2_A_C  BI  = M_D_CPU0_SA_DQS_DN<2>
  35  VSS13  POWER  = GND
  36  DQ20_A  BI  = M_D_CPU0_SA_DQ<20>
  37  VSS14  POWER  = GND
  38  DQ21_A  BI  = M_D_CPU0_SA_DQ<21>
  39  VSS15  POWER  = GND
  40  DQ24_A  BI  = M_D_CPU0_SA_DQ<24>
  41  VSS16  POWER  = GND
  42  DQ25_A  BI  = M_D_CPU0_SA_DQ<25>
  43  VSS17  POWER  = GND
  44  DQS3_A_T  BI  = M_D_CPU0_SA_DQS_DP<3>
  45  DQS3_A_C  BI  = M_D_CPU0_SA_DQS_DN<3>
  46  VSS18  POWER  = GND
  47  DQ28_A  BI  = M_D_CPU0_SA_DQ<28>
  48  VSS19  POWER  = GND
  49  DQ29_A  BI  = M_D_CPU0_SA_DQ<29>
  50  VSS20  POWER  = GND
  51  CB0_A  BI  = M_D_CPU0_SA_CB<0>
  52  VSS21  POWER  = GND
  53  CB1_A  BI  = M_D_CPU0_SA_CB<1>
  54  VSS22  POWER  = GND
  55  DQS4_A_T  BI  = M_D_CPU0_SA_DQS_DP<4>
  56  DQS4_A_C  BI  = M_D_CPU0_SA_DQS_DN<4>
  57  VSS23  POWER  = GND
  58  CB4_A  BI  = M_D_CPU0_SA_CB<4>
  59  VSS24  POWER  = GND
  60  CB5_A  BI  = M_D_CPU0_SA_CB<5>
  61  VSS25  POWER  = GND
  62  ALERT_N  OUT  = M_D_CPU0_ALERT_N
  63  VSS26  POWER  = GND
  64  CS0_A_N  IN  = M_D_CPU0_SA_CS_N<2>
  65  VSS27  POWER  = GND
  66  CA0_A  IN  = M_D_CPU0_SA_CA<0>
  67  VSS28  POWER  = GND
  68  CA2_A  IN  = M_D_CPU0_SA_CA<2>
  69  VSS29  POWER  = GND
  70  CA4_A  IN  = M_D_CPU0_SA_CA<4>
  71  VSS30  POWER  = GND
  72  CA6_A  IN  = M_D_CPU0_SA_CA<6>
  73  VSS31  POWER  = GND
  74  PAR_A  IN  = M_D_CPU0_SA_PAR
  75  VSS32  POWER  = GND
  76  CA0_B  IN  = M_D_CPU0_SB_CA<0>
  77  VSS33  POWER  = GND
  78  CA2_B  IN  = M_D_CPU0_SB_CA<2>
  79  VSS34  POWER  = GND
  80  CA4_B  IN  = M_D_CPU0_SB_CA<4>
  81  VSS35  POWER  = GND
  82  CA6_B  IN  = M_D_CPU0_SB_CA<6>
  83  VSS36  POWER  = GND
  84  CS0_B_N  IN  = M_D_CPU0_SB_CS_N<2>
  85  VSS37  POWER  = GND
  86  \lbd||rsp_a_n\  OUT  = M_D_CPU0_SA_RSP<1>
  87  \lbs||rsp_b_n\  OUT  = M_D_CPU0_SB_RSP<1>
  88  VSS38  POWER  = GND
  89  CB4_B  BI  = M_D_CPU0_SB_CB<4>
  90  VSS39  POWER  = GND
  91  CB5_B  BI  = M_D_CPU0_SB_CB<5>
  92  VSS40  POWER  = GND
  93  \dqs9_b_t||tdqs9_b_t||dbi4_b_n\  BI  = M_D_CPU0_SB_DQS_DP<9>
  94  \dqs9_b_c||tdqs9_b_c\  BI  = M_D_CPU0_SB_DQS_DN<9>
  95  VSS41  POWER  = GND
  96  CB0_B  BI  = M_D_CPU0_SB_CB<0>
  97  VSS42  POWER  = GND
  98  CB1_B  BI  = M_D_CPU0_SB_CB<1>
  99  VSS43  POWER  = GND
  100  DQ0_B  BI  = M_D_CPU0_SB_DQ<0>
  101  VSS44  POWER  = GND
  102  DQ1_B  BI  = M_D_CPU0_SB_DQ<1>
  103  VSS45  POWER  = GND
  104  DQS0_B_T  BI  = M_D_CPU0_SB_DQS_DP<0>
  105  DQS0_B_C  BI  = M_D_CPU0_SB_DQS_DN<0>
  106  VSS46  POWER  = GND
  107  DQ4_B  BI  = M_D_CPU0_SB_DQ<4>
  108  VSS47  POWER  = GND
  109  DQ5_B  BI  = M_D_CPU0_SB_DQ<5>
  110  VSS48  POWER  = GND
  111  DQ8_B  BI  = M_D_CPU0_SB_DQ<8>
  112  VSS49  POWER  = GND
  113  DQ9_B  BI  = M_D_CPU0_SB_DQ<9>
  114  VSS50  POWER  = GND
  115  DQS1_B_T  BI  = M_D_CPU0_SB_DQS_DP<1>
  116  DQS1_B_C  BI  = M_D_CPU0_SB_DQS_DN<1>
  117  VSS51  POWER  = GND
  118  DQ12_B  BI  = M_D_CPU0_SB_DQ<12>
  119  VSS52  POWER  = GND
  120  DQ13_B  BI  = M_D_CPU0_SB_DQ<13>
  121  VSS53  POWER  = GND
  122  DQ16_B  BI  = M_D_CPU0_SB_DQ<16>
  123  VSS54  POWER  = GND
  124  DQ17_B  BI  = M_D_CPU0_SB_DQ<17>
  125  VSS55  POWER  = GND
  126  DQS2_B_T  BI  = M_D_CPU0_SB_DQS_DP<2>
  127  DQS2_B_C  BI  = M_D_CPU0_SB_DQS_DN<2>
  128  VSS56  POWER  = GND
  129  DQ20_B  BI  = M_D_CPU0_SB_DQ<20>
  130  VSS57  POWER  = GND
  131  DQ21_B  BI  = M_D_CPU0_SB_DQ<21>
  132  VSS58  POWER  = GND
  133  DQ24_B  BI  = M_D_CPU0_SB_DQ<24>
  134  VSS59  POWER  = GND
  135  DQ25_B  BI  = M_D_CPU0_SB_DQ<25>
  136  VSS60  POWER  = GND
  137  DQS3_B_T  BI  = M_D_CPU0_SB_DQS_DP<3>
  138  DQS3_B_C  BI  = M_D_CPU0_SB_DQS_DN<3>
  139  VSS61  POWER  = GND
  140  DQ28_B  BI  = M_D_CPU0_SB_DQ<28>
  141  VSS62  POWER  = GND
  142  DQ29_B  BI  = M_D_CPU0_SB_DQ<29>
  143  VSS63  POWER  = GND
  144  RFU1  TRI  = TP_CHD_CPU0_DIMM2_FRU_1
  145  VIN_BULK1  POWER  = P12V_S3_AUX_CPU0_NVDIMM
  146  VIN_BULK2  POWER  = P12V_S3_AUX_CPU0_NVDIMM
  147  \pwr_good||fail_n\  BI  = PWRGD_CHD_CPU0_DIMM2
  148  HSA  IN  = PD_CHD_CPU0_DIMM2_SAA
  149  RFU2  TRI  = TP_CHD_CPU0_DIMM2_FRU_2
  150  RFU3  TRI  = TP_CHD_CPU0_DIMM2_FRU_3
  151  VSS64  POWER  = GND
  152  DQ2_A  BI  = M_D_CPU0_SA_DQ<2>
  153  VSS65  POWER  = GND
  154  DQ3_A  BI  = M_D_CPU0_SA_DQ<3>
  155  VSS66  POWER  = GND
  156  \dqs5_a_c||tdqs5_a_c||dqs5_a_t||tdqs5_a_t\  BI  = M_D_CPU0_SA_DQS_DN<5>
  157  \dqs5_a_t||tdqs5_a_t\  BI  = M_D_CPU0_SA_DQS_DP<5>
  158  VSS67  POWER  = GND
  159  DQ6_A  BI  = M_D_CPU0_SA_DQ<6>
  160  VSS68  POWER  = GND
  161  DQ7_A  BI  = M_D_CPU0_SA_DQ<7>
  162  VSS69  POWER  = GND
  163  DQ10_A  BI  = M_D_CPU0_SA_DQ<10>
  164  VSS70  POWER  = GND
  165  DQ11_A  BI  = M_D_CPU0_SA_DQ<11>
  166  VSS71  POWER  = GND
  167  \dqs6_a_c||tdqs6_a_c||dqs6_a_t||tdqs6_a_t\  BI  = M_D_CPU0_SA_DQS_DN<6>
  168  \dqs6_a_t||tdqs6_a_t\  BI  = M_D_CPU0_SA_DQS_DP<6>
  169  VSS72  POWER  = GND
  170  DQ14_A  BI  = M_D_CPU0_SA_DQ<14>
  171  VSS73  POWER  = GND
  172  DQ15_A  BI  = M_D_CPU0_SA_DQ<15>
  173  VSS74  POWER  = GND
  174  DQ18_A  BI  = M_D_CPU0_SA_DQ<18>
  175  VSS75  POWER  = GND
  176  DQ19_A  BI  = M_D_CPU0_SA_DQ<19>
  177  VSS76  POWER  = GND
  178  \dqs7_a_c||tdqs7_a_c\  BI  = M_D_CPU0_SA_DQS_DN<7>
  179  \dqs7_a_t||tdqs7_a_t\  BI  = M_D_CPU0_SA_DQS_DP<7>
  180  VSS77  POWER  = GND
  181  DQ22_A  BI  = M_D_CPU0_SA_DQ<22>
  182  VSS78  POWER  = GND
  183  DQ23_A  BI  = M_D_CPU0_SA_DQ<23>
  184  VSS79  POWER  = GND
  185  DQ26_A  BI  = M_D_CPU0_SA_DQ<26>
  186  VSS80  POWER  = GND
  187  DQ27_A  BI  = M_D_CPU0_SA_DQ<27>
  188  VSS81  POWER  = GND
  189  \dqs8_a_c||tdqs8_a_c\  BI  = M_D_CPU0_SA_DQS_DN<8>
  190  \dqs8_a_t||tdqs8_a_t\  BI  = M_D_CPU0_SA_DQS_DP<8>
  191  VSS82  POWER  = GND
  192  DQ30_A  BI  = M_D_CPU0_SA_DQ<30>
  193  VSS83  POWER  = GND
  194  DQ31_A  BI  = M_D_CPU0_SA_DQ<31>
  195  VSS84  POWER  = GND
  196  CB2_A  BI  = M_D_CPU0_SA_CB<2>
  197  VSS85  POWER  = GND
  198  CB3_A  BI  = M_D_CPU0_SA_CB<3>
  199  VSS86  POWER  = GND
  200  \dqs9_a_c||tdqs9_a_c\  BI  = M_D_CPU0_SA_DQS_DN<9>
  201  \dqs9_a_t||tdqs9_a_t\  BI  = M_D_CPU0_SA_DQS_DP<9>
  202  VSS87  POWER  = GND
  203  CB6_A  BI  = M_D_CPU0_SA_CB<6>
  204  VSS88  POWER  = GND
  205  CB7_A  BI  = M_D_CPU0_SA_CB<7>
  206  VSS89  POWER  = GND
  207  RESET_N  IN  = RST_M_CD_CPU0_FPGA_N
  208  VSS90  POWER  = GND
  209  CS1_A_N  IN  = M_D_CPU0_SA_CS_N<3>
  210  VSS91  POWER  = GND
  211  CA1_A  IN  = M_D_CPU0_SA_CA<1>
  212  VSS92  POWER  = GND
  213  CA3_A  IN  = M_D_CPU0_SA_CA<3>
  214  VSS93  POWER  = GND
  215  CA5_A  IN  = M_D_CPU0_SA_CA<5>
  216  VSS94  POWER  = GND
  217  CK_T  IN  = M_D_CPU0_CLK_DP<1>
  218  CK_C  IN  = M_D_CPU0_CLK_DN<1>
  219  VSS95  POWER  = GND
  220  RFU4  TRI  = TP_CHD_CPU0_DIMM2_FRU_4
  221  CA1_B  IN  = M_D_CPU0_SB_CA<1>
  222  VSS96  POWER  = GND
  223  CA3_B  IN  = M_D_CPU0_SB_CA<3>
  224  VSS97  POWER  = GND
  225  CA5_B  IN  = M_D_CPU0_SB_CA<5>
  226  VSS98  POWER  = GND
  227  PAR_B  IN  = M_D_CPU0_SB_PAR
  228  VSS99  POWER  = GND
  229  CS1_B_N  IN  = M_D_CPU0_SB_CS_N<3>
  230  VSS100  POWER  = GND
  231  RFU5  TRI  = TP_CHD_CPU0_DIMM2_FRU_5
  232  RFU6  TRI  = TP_CHD_CPU0_DIMM2_FRU_6
  233  VSS101  POWER  = GND
  234  CB6_B  BI  = M_D_CPU0_SB_CB<6>
  235  VSS102  POWER  = GND
  236  CB7_B  BI  = M_D_CPU0_SB_CB<7>
  237  VSS103  POWER  = GND
  238  DQS4_B_C  BI  = M_D_CPU0_SB_DQS_DN<4>
  239  DQS4_B_T  BI  = M_D_CPU0_SB_DQS_DP<4>
  240  VSS104  POWER  = GND
  241  CB2_B  BI  = M_D_CPU0_SB_CB<2>
  242  VSS105  POWER  = GND
  243  CB3_B  BI  = M_D_CPU0_SB_CB<3>
  244  VSS106  POWER  = GND
  245  DQ2_B  BI  = M_D_CPU0_SB_DQ<2>
  246  VSS107  POWER  = GND
  247  DQ3_B  BI  = M_D_CPU0_SB_DQ<3>
  248  VSS108  POWER  = GND
  249  \dqs5_b_c||tdqs5_b_c\  BI  = M_D_CPU0_SB_DQS_DN<5>
  250  \dqs5_b_t||tdqs5_b_t\  BI  = M_D_CPU0_SB_DQS_DP<5>
  251  VSS109  POWER  = GND
  252  DQ6_B  BI  = M_D_CPU0_SB_DQ<6>
  253  VSS110  POWER  = GND
  254  DQ7_B  BI  = M_D_CPU0_SB_DQ<7>
  255  VSS111  POWER  = GND
  256  DQ10_B  BI  = M_D_CPU0_SB_DQ<10>
  257  VSS112  POWER  = GND
  258  DQ11_B  BI  = M_D_CPU0_SB_DQ<11>
  259  VSS113  POWER  = GND
  260  \dqs6_b_c||tdqs6_b_c\  BI  = M_D_CPU0_SB_DQS_DN<6>
  261  \dqs6_b_t||tdqs6_b_t\  BI  = M_D_CPU0_SB_DQS_DP<6>
  262  VSS114  POWER  = GND
  263  DQ14_B  BI  = M_D_CPU0_SB_DQ<14>
  264  VSS115  POWER  = GND
  265  DQ15_B  BI  = M_D_CPU0_SB_DQ<15>
  266  VSS116  POWER  = GND
  267  DQ18_B  BI  = M_D_CPU0_SB_DQ<18>
  268  VSS117  POWER  = GND
  269  DQ19_B  BI  = M_D_CPU0_SB_DQ<19>
  270  VSS118  POWER  = GND
  271  \dqs7_b_c||tdqs7_b_c\  BI  = M_D_CPU0_SB_DQS_DN<7>
  272  \dqs7_b_t||tdqs7_b_t\  BI  = M_D_CPU0_SB_DQS_DP<7>
  273  VSS119  POWER  = GND
  274  DQ22_B  BI  = M_D_CPU0_SB_DQ<22>
  275  VSS120  POWER  = GND
  276  DQ23_B  BI  = M_D_CPU0_SB_DQ<23>
  277  VSS121  POWER  = GND
  278  DQ26_B  BI  = M_D_CPU0_SB_DQ<26>
  279  VSS122  POWER  = GND
  280  DQ27_B  BI  = M_D_CPU0_SB_DQ<27>
  281  VSS123  POWER  = GND
  282  \dqs8_b_c||tdqs8_b_c\  BI  = M_D_CPU0_SB_DQS_DN<8>
  283  \dqs8_b_t||tdqs8_b_t\  BI  = M_D_CPU0_SB_DQS_DP<8>
  284  VSS124  POWER  = GND
  285  DQ30_B  BI  = M_D_CPU0_SB_DQ<30>
  286  VSS125  POWER  = GND
  287  DQ31_B  BI  = M_D_CPU0_SB_DQ<31>
  288  VSS126  POWER  = GND
  G1  G1  POWER  = GND
  G2  G2  POWER  = GND
  G3  G3  POWER  = GND
